# BASEBOARD_FAB2 (Tioga Pass) — schematic netlist excerpt (pin names and nets, part order shuffled) for the footprints in the layout excerpt that follows; sources: Cadence DE-HDL packaged netlist, KiCad conversion of Wiwynn_Tioga_Pass_MB.brd

R4G2  RES  1.00K 1% CHIP  pkg 0402  page 98 : A = PVDDQ_ABC ; B = M_B_VREF
R7A10  RES  16K 1.0% CHIP  pkg 0402  page 218 : A = VR_PVDDQ_DEF_XADDR1 ; B = GND
R1W16  RES  0.0 5% CHIP  pkg 0402  page 115 : A = USB_PCH_BMC_P4_DP_R ; B = USB_PCH_BMC_P4_DP

(kicad_pcb
	(version 20260206)
	(generator "pcbnew")
	(generator_version "10.0")
	(general
		(thickness 1.6)
		(legacy_teardrops no)
	)
	(paper "A4")
	(title_block
		(title "Wiwynn_Tioga_Pass_MB.brd")
		(comment 1 "Tioga Pass / footprints 1668-1670 of 4770")
	)
	(layers
		(0 "F.Cu" signal "TOP")
		(4 "In1.Cu" signal "L2GND")
		(6 "In2.Cu" signal "L3")
		(8 "In3.Cu" signal "L4GND")
		(10 "In4.Cu" signal "L5")
		(12 "In5.Cu" signal "L6GND")
		(14 "In6.Cu" signal "L7VCC")
		(16 "In7.Cu" signal "L8VCC")
		(18 "In8.Cu" signal "L9GND")
		(20 "In9.Cu" signal "L10")
		(22 "In10.Cu" signal "L11GND")
		(24 "In11.Cu" signal "L12")
		(26 "In12.Cu" signal "L13GND")
		(2 "B.Cu" signal "BOTTOM")
		(9 "F.Adhes" user "F.Adhesive")
		(11 "B.Adhes" user "B.Adhesive")
		(13 "F.Paste" user "Package Geometry/Pastemask Top")
		(15 "B.Paste" user "Package Geometry/Pastemask Bottom")
		(5 "F.SilkS" user "Ref Des/Silkscreen Top")
		(7 "B.SilkS" user "Ref Des/Silkscreen Bottom")
		(1 "F.Mask" user "Board Geometry/Soldermask Top")
		(3 "B.Mask" user "Board Geometry/Soldermask Bottom")
		(17 "Dwgs.User" user "User.Drawings")
		(19 "Cmts.User" user "User.Comments")
		(21 "Eco1.User" user "User.Eco1")
		(23 "Eco2.User" user "User.Eco2")
		(25 "Edge.Cuts" user "Board Geometry/Outline")
		(27 "Margin" user)
		(31 "F.CrtYd" user "Package Geometry/Place Bound Top")
		(29 "B.CrtYd" user "Package Geometry/Place Bound Bottom")
		(35 "F.Fab" user "Ref Des/Assembly Top")
		(33 "B.Fab" user "Ref Des/Assembly Bottom")
	)
	(footprint ""
		(layer "F.Cu")
		(at 407.749502 -122.011186 90)
		(property "Reference" "R1W16"
			(at -0.8382 -0.67818 90)
			(unlocked yes)
			(layer "F.SilkS")
			(effects
				(font
					(size 0.4064 0.254)
					(thickness 0.1524)
				)
				(justify left)
			)
		)
		(property "Value" ""
			(at 0 0 90)
			(layer "F.Fab")
			(effects
				(font
					(size 1.27 1.27)
				)
			)
		)
		(duplicate_pad_numbers_are_jumpers no)
		(fp_poly
			(pts
				(xy -0.2794 -0.1016) (xy 0.2794 -0.1016) (xy 0.2794 0.9906) (xy -0.2794 0.9906)
			)
			(stroke
				(width 0)
				(type default)
			)
			(fill no)
			(layer "F.CrtYd")
		)
		(fp_line
			(start 0.2794 -0.1016)
			(end -0.2794 -0.1016)
			(stroke
				(width 0.1)
				(type default)
			)
			(layer "F.Fab")
		)
		(fp_line
			(start -0.2794 -0.1016)
			(end -0.2794 0.9906)
			(stroke
				(width 0.1)
				(type default)
			)
			(layer "F.Fab")
		)
		(fp_line
			(start 0.2794 0.9906)
			(end 0.2794 -0.1016)
			(stroke
				(width 0.1)
				(type default)
			)
			(layer "F.Fab")
		)
		(fp_line
			(start -0.2794 0.9906)
			(end 0.2794 0.9906)
			(stroke
				(width 0.1)
				(type default)
			)
			(layer "F.Fab")
		)
		(pad "1" smd rect
			(at 0 0 90)
			(size 0.508 0.508)
			(layers "F.Cu" "F.Mask" "F.Paste")
			(net "USB_PCH_BMC_P4_DP_R")
		)
		(pad "2" smd rect
			(at 0 0.889 90)
			(size 0.508 0.508)
			(layers "F.Cu" "F.Mask" "F.Paste")
			(net "USB_PCH_BMC_P4_DP")
		)
		(zone
			(layer "F.Cu")
			(hatch none 0.5)
			(connect_pads
				(clearance 0)
			)
			(min_thickness 0.25)
			(keepout
				(tracks allowed)
				(vias not_allowed)
				(pads allowed)
				(copperpour not_allowed)
				(footprints allowed)
			)
			(placement
				(enabled no)
				(sheetname "")
			)
			(fill
				(thermal_gap 0.5)
				(thermal_bridge_width 0.5)
				(island_removal_mode 0)
			)
			(polygon
				(pts
					(xy 408.003502 -121.757186) (xy 408.003502 -122.265186) (xy 408.384502 -122.265186) (xy 408.384502 -121.757186)
				)
			)
		)
		(zone
			(layer "F.Cu")
			(hatch none 0.5)
			(connect_pads
				(clearance 0)
			)
			(min_thickness 0.25)
			(keepout
				(tracks not_allowed)
				(vias allowed)
				(pads allowed)
				(copperpour not_allowed)
				(footprints allowed)
			)
			(placement
				(enabled no)
				(sheetname "")
			)
			(fill
				(thermal_gap 0.5)
				(thermal_bridge_width 0.5)
				(island_removal_mode 0)
			)
			(polygon
				(pts
					(xy 408.384502 -121.757186) (xy 408.384502 -122.265186) (xy 408.003502 -122.265186) (xy 408.003502 -121.757186)
				)
			)
		)
	)
	(footprint ""
		(layer "F.Cu")
		(at 351.51568 -139.37742 -90)
		(property "Reference" "R7A10"
			(at 0 0 270)
			(layer "F.SilkS")
			(hide yes)
			(effects
				(font
					(size 1.27 1.27)
				)
			)
		)
		(property "Value" ""
			(at 0 0 270)
			(layer "F.Fab")
			(effects
				(font
					(size 1.27 1.27)
				)
			)
		)
		(duplicate_pad_numbers_are_jumpers no)
		(fp_poly
			(pts
				(xy -0.2794 -0.1016) (xy 0.2794 -0.1016) (xy 0.2794 0.9906) (xy -0.2794 0.9906)
			)
			(stroke
				(width 0)
				(type default)
			)
			(fill no)
			(layer "F.CrtYd")
		)
		(fp_line
			(start -0.2794 0.9906)
			(end 0.2794 0.9906)
			(stroke
				(width 0.1)
				(type default)
			)
			(layer "F.Fab")
		)
		(fp_line
			(start 0.2794 0.9906)
			(end 0.2794 -0.1016)
			(stroke
				(width 0.1)
				(type default)
			)
			(layer "F.Fab")
		)
		(fp_line
			(start -0.2794 -0.1016)
			(end -0.2794 0.9906)
			(stroke
				(width 0.1)
				(type default)
			)
			(layer "F.Fab")
		)
		(fp_line
			(start 0.2794 -0.1016)
			(end -0.2794 -0.1016)
			(stroke
				(width 0.1)
				(type default)
			)
			(layer "F.Fab")
		)
		(pad "1" smd rect
			(at 0 0 270)
			(size 0.508 0.508)
			(layers "F.Cu" "F.Mask" "F.Paste")
			(net "VR_PVDDQ_DEF_XADDR1")
		)
		(pad "2" smd rect
			(at 0 0.889 270)
			(size 0.508 0.508)
			(layers "F.Cu" "F.Mask" "F.Paste")
			(net "GND")
		)
		(zone
			(layer "F.Cu")
			(hatch none 0.5)
			(connect_pads
				(clearance 0)
			)
			(min_thickness 0.25)
			(keepout
				(tracks not_allowed)
				(vias allowed)
				(pads allowed)
				(copperpour not_allowed)
				(footprints allowed)
			)
			(placement
				(enabled no)
				(sheetname "")
			)
			(fill
				(thermal_gap 0.5)
				(thermal_bridge_width 0.5)
				(island_removal_mode 0)
			)
			(polygon
				(pts
					(xy 350.88068 -139.63142) (xy 350.88068 -139.12342) (xy 351.26168 -139.12342) (xy 351.26168 -139.63142)
				)
			)
		)
		(zone
			(layer "F.Cu")
			(hatch none 0.5)
			(connect_pads
				(clearance 0)
			)
			(min_thickness 0.25)
			(keepout
				(tracks allowed)
				(vias not_allowed)
				(pads allowed)
				(copperpour not_allowed)
				(footprints allowed)
			)
			(placement
				(enabled no)
				(sheetname "")
			)
			(fill
				(thermal_gap 0.5)
				(thermal_bridge_width 0.5)
				(island_removal_mode 0)
			)
			(polygon
				(pts
					(xy 351.26168 -139.63142) (xy 351.26168 -139.12342) (xy 350.88068 -139.12342) (xy 350.88068 -139.63142)
				)
			)
		)
	)
	(footprint ""
		(layer "F.Cu")
		(at 193.675 -13.3985)
		(property "Reference" "R4G2"
			(at 0 0 0)
			(layer "F.SilkS")
			(hide yes)
			(effects
				(font
					(size 1.27 1.27)
				)
			)
		)
		(property "Value" ""
			(at 0 0 0)
			(layer "F.Fab")
			(effects
				(font
					(size 1.27 1.27)
				)
			)
		)
		(duplicate_pad_numbers_are_jumpers no)
		(fp_poly
			(pts
				(xy -0.2794 -0.1016) (xy 0.2794 -0.1016) (xy 0.2794 0.9906) (xy -0.2794 0.9906)
			)
			(stroke
				(width 0)
				(type default)
			)
			(fill no)
			(layer "F.CrtYd")
		)
		(fp_line
			(start -0.2794 -0.1016)
			(end -0.2794 0.9906)
			(stroke
				(width 0.1)
				(type default)
			)
			(layer "F.Fab")
		)
		(fp_line
			(start -0.2794 0.9906)
			(end 0.2794 0.9906)
			(stroke
				(width 0.1)
				(type default)
			)
			(layer "F.Fab")
		)
		(fp_line
			(start 0.2794 -0.1016)
			(end -0.2794 -0.1016)
			(stroke
				(width 0.1)
				(type default)
			)
			(layer "F.Fab")
		)
		(fp_line
			(start 0.2794 0.9906)
			(end 0.2794 -0.1016)
			(stroke
				(width 0.1)
				(type default)
			)
			(layer "F.Fab")
		)
		(pad "1" smd rect
			(at 0 0)
			(size 0.508 0.508)
			(layers "F.Cu" "F.Mask" "F.Paste")
			(net "PVDDQ_ABC")
		)
		(pad "2" smd rect
			(at 0 0.889)
			(size 0.508 0.508)
			(layers "F.Cu" "F.Mask" "F.Paste")
			(net "M_B_VREF")
		)
		(zone
			(layer "F.Cu")
			(hatch none 0.5)
			(connect_pads
				(clearance 0)
			)
			(min_thickness 0.25)
			(keepout
				(tracks allowed)
				(vias not_allowed)
				(pads allowed)
				(copperpour not_allowed)
				(footprints allowed)
			)
			(placement
				(enabled no)
				(sheetname "")
			)
			(fill
				(thermal_gap 0.5)
				(thermal_bridge_width 0.5)
				(island_removal_mode 0)
			)
			(polygon
				(pts
					(xy 193.421 -13.1445) (xy 193.929 -13.1445) (xy 193.929 -12.7635) (xy 193.421 -12.7635)
				)
			)
		)
		(zone
			(layer "F.Cu")
			(hatch none 0.5)
			(connect_pads
				(clearance 0)
			)
			(min_thickness 0.25)
			(keepout
				(tracks not_allowed)
				(vias allowed)
				(pads allowed)
				(copperpour not_allowed)
				(footprints allowed)
			)
			(placement
				(enabled no)
				(sheetname "")
			)
			(fill
				(thermal_gap 0.5)
				(thermal_bridge_width 0.5)
				(island_removal_mode 0)
			)
			(polygon
				(pts
					(xy 193.421 -12.7635) (xy 193.929 -12.7635) (xy 193.929 -13.1445) (xy 193.421 -13.1445)
				)
			)
		)
	)
)
